(kicad_pcb
	(version 20260206)
	(generator "pcbnew")
	(generator_version "10.0")
	(general
		(thickness 1.6)
		(legacy_teardrops no)
	)
	(paper "A4")
	(title_block
		(title "Bryce Canyon_F.DPB_16315-1-OCP.brd")
		(comment 1 "Bryce Canyon / footprints 2201-2207 of 2223")
	)
	(layers
		(0 "F.Cu" signal "TOP")
		(4 "In1.Cu" signal "L2GND")
		(6 "In2.Cu" signal "L3")
		(8 "In3.Cu" signal "L4GND")
		(10 "In4.Cu" signal "L5")
		(12 "In5.Cu" signal "L6VCC")
		(14 "In6.Cu" signal "L7VCC")
		(16 "In7.Cu" signal "L8")
		(18 "In8.Cu" signal "L9GND")
		(20 "In9.Cu" signal "L10")
		(22 "In10.Cu" signal "L11GND")
		(2 "B.Cu" signal "BOTTOM")
		(9 "F.Adhes" user "F.Adhesive")
		(11 "B.Adhes" user "B.Adhesive")
		(13 "F.Paste" user "Package Geometry/Pastemask Top")
		(15 "B.Paste" user "Package Geometry/Pastemask Bottom")
		(5 "F.SilkS" user "Ref Des/Silkscreen Top")
		(7 "B.SilkS" user "Ref Des/Silkscreen Bottom")
		(1 "F.Mask" user "Board Geometry/Soldermask Top")
		(3 "B.Mask" user "Board Geometry/Soldermask Bottom")
		(17 "Dwgs.User" user "User.Drawings")
		(19 "Cmts.User" user "User.Comments")
		(21 "Eco1.User" user "User.Eco1")
		(23 "Eco2.User" user "User.Eco2")
		(25 "Edge.Cuts" user "Board Geometry/Outline")
		(27 "Margin" user)
		(31 "F.CrtYd" user "Package Geometry/Place Bound Top")
		(29 "B.CrtYd" user "Package Geometry/Place Bound Bottom")
		(35 "F.Fab" user "Ref Des/Assembly Top")
		(33 "B.Fab" user "Ref Des/Assembly Bottom")
	)
	(footprint ""
		(layer "B.Cu")
		(at 482.219 -233.934 90)
		(property "Reference" "R1276"
			(at 0 0 90)
			(layer "B.SilkS")
			(hide yes)
			(effects
				(font
					(size 1.27 1.27)
				)
				(justify mirror)
			)
		)
		(property "Value" "309KR2F-GP"
			(at -0.064008 -3.993896 90)
			(unlocked yes)
			(layer "B.Fab")
			(hide yes)
			(effects
				(font
					(size 1.016 1.016)
					(thickness 0.1524)
				)
				(justify mirror)
			)
		)
		(property "Device Type" "R402H16"
			(at -0.064008 -5.517896 90)
			(unlocked yes)
			(layer "B.Fab")
			(hide yes)
			(effects
				(font
					(size 1.016 1.016)
					(thickness 0.1524)
				)
				(justify mirror)
			)
		)
		(duplicate_pad_numbers_are_jumpers no)
		(fp_line
			(start 0.508 -0.9398)
			(end 0.508 0.9398)
			(stroke
				(width 0.1524)
				(type default)
			)
			(layer "B.SilkS")
		)
		(fp_line
			(start -0.508 -0.9398)
			(end 0.508 -0.9398)
			(stroke
				(width 0.1524)
				(type default)
			)
			(layer "B.SilkS")
		)
		(fp_rect
			(start 0.508 0.9398)
			(end -0.508 -0.9398)
			(stroke
				(width 0)
				(type default)
			)
			(fill no)
			(layer "B.CrtYd")
		)
		(fp_rect
			(start 0.508 0.9398)
			(end -0.508 -0.9398)
			(stroke
				(width 0)
				(type default)
			)
			(fill no)
			(layer "B.Fab")
		)
		(pad "1" smd custom
			(at 0 -0.4445 270)
			(size 0.1397 0.1397)
			(layers "B.Cu" "B.Mask" "B.Paste")
			(net "P5V_D_RF")
			(options
				(clearance outline)
				(anchor circle)
			)
			(primitives
				(gr_poly
					(pts
						(arc
							(start -0.1778 0.2794)
							(mid -0.249642 0.249642)
							(end -0.2794 0.1778)
						)
						(arc
							(start -0.2794 -0.1778)
							(mid -0.249642 -0.249642)
							(end -0.1778 -0.2794)
						)
						(arc
							(start 0.1778 -0.2794)
							(mid 0.249642 -0.249642)
							(end 0.2794 -0.1778)
						)
						(arc
							(start 0.2794 0.1778)
							(mid 0.249642 0.249642)
							(end 0.1778 0.2794)
						)
					)
					(width 0)
					(fill yes)
				)
			)
		)
		(pad "2" smd custom
			(at 0 0.4445 270)
			(size 0.1397 0.1397)
			(layers "B.Cu" "B.Mask" "B.Paste")
			(net "P5V_D_VREG")
			(options
				(clearance outline)
				(anchor circle)
			)
			(primitives
				(gr_poly
					(pts
						(arc
							(start -0.1778 0.2794)
							(mid -0.249642 0.249642)
							(end -0.2794 0.1778)
						)
						(arc
							(start -0.2794 -0.1778)
							(mid -0.249642 -0.249642)
							(end -0.1778 -0.2794)
						)
						(arc
							(start 0.1778 -0.2794)
							(mid 0.249642 -0.249642)
							(end 0.2794 -0.1778)
						)
						(arc
							(start 0.2794 0.1778)
							(mid 0.249642 0.249642)
							(end 0.1778 0.2794)
						)
					)
					(width 0)
					(fill yes)
				)
			)
		)
	)
	(footprint ""
		(layer "B.Cu")
		(at 65.5574 -149.3012 180)
		(property "Reference" "TC6"
			(at 0 0 0)
			(layer "B.SilkS")
			(hide yes)
			(effects
				(font
					(size 1.27 1.27)
				)
				(justify mirror)
			)
		)
		(property "Value" "ST220U10VDM-LGP"
			(at 0 -9.6012 180)
			(unlocked yes)
			(layer "B.Fab")
			(hide yes)
			(effects
				(font
					(size 1.016 1.016)
					(thickness 0.1524)
				)
				(justify mirror)
			)
		)
		(property "Device Type" "CT7343H119"
			(at 0 -11.1252 180)
			(unlocked yes)
			(layer "B.Fab")
			(hide yes)
			(effects
				(font
					(size 1.016 1.016)
					(thickness 0.1524)
				)
				(justify mirror)
			)
		)
		(duplicate_pad_numbers_are_jumpers no)
		(fp_line
			(start 2.286 4.8768)
			(end 2.286 2.032)
			(stroke
				(width 0.1524)
				(type default)
			)
			(layer "B.SilkS")
		)
		(fp_line
			(start 2.286 -4.8768)
			(end 2.286 -2.032)
			(stroke
				(width 0.1524)
				(type default)
			)
			(layer "B.SilkS")
		)
		(fp_line
			(start -2.1082 -4.699)
			(end 2.1082 -4.699)
			(stroke
				(width 0.508)
				(type default)
			)
			(layer "B.SilkS")
		)
		(fp_line
			(start -2.286 4.8768)
			(end 2.286 4.8768)
			(stroke
				(width 0.1524)
				(type default)
			)
			(layer "B.SilkS")
		)
		(fp_line
			(start -2.286 2.032)
			(end -2.286 4.8768)
			(stroke
				(width 0.1524)
				(type default)
			)
			(layer "B.SilkS")
		)
		(fp_line
			(start -2.286 -2.032)
			(end -2.286 -4.8768)
			(stroke
				(width 0.1524)
				(type default)
			)
			(layer "B.SilkS")
		)
		(fp_line
			(start -2.286 -4.8768)
			(end 2.286 -4.8768)
			(stroke
				(width 0.1524)
				(type default)
			)
			(layer "B.SilkS")
		)
		(fp_rect
			(start 2.1463 3.6449)
			(end -2.1463 -3.6449)
			(stroke
				(width 0)
				(type default)
			)
			(fill no)
			(layer "B.CrtYd")
		)
		(fp_poly
			(pts
				(xy 2.54 4.953) (xy 2.54 4.2926) (xy 3.81 4.2926) (xy 3.81 -4.2926) (xy 2.54 -4.2926) (xy 2.54 -4.953)
				(xy -2.54 -4.953) (xy -2.54 -4.2926) (xy -3.81 -4.2926) (xy -3.81 -1.6256) (xy -2.1463 -1.6256)
				(xy -2.1463 -3.6449) (xy 2.1463 -3.6449) (xy 2.1463 3.6449) (xy -2.1463 3.6449) (xy -2.1463 -1.6129)
				(xy -3.81 -1.6129) (xy -3.81 4.2926) (xy -2.54 4.2926) (xy -2.54 4.953)
			)
			(stroke
				(width 0)
				(type default)
			)
			(fill no)
			(layer "B.CrtYd")
		)
		(fp_rect
			(start 3.81 4.2926)
			(end 2.54 -4.2926)
			(stroke
				(width 0)
				(type default)
			)
			(fill no)
			(layer "B.Fab")
		)
		(fp_rect
			(start 2.54 4.953)
			(end -2.54 -4.953)
			(stroke
				(width 0)
				(type default)
			)
			(fill no)
			(layer "B.Fab")
		)
		(fp_rect
			(start -2.54 4.2926)
			(end -3.81 -4.2926)
			(stroke
				(width 0)
				(type default)
			)
			(fill no)
			(layer "B.Fab")
		)
		(pad "1" smd rect
			(at 0 -3.1496)
			(size 2.413 2.286)
			(layers "B.Cu" "B.Mask" "B.Paste")
			(net "P5V_A_2")
		)
		(pad "2" smd rect
			(at 0 3.1496)
			(size 2.413 2.286)
			(layers "B.Cu" "B.Mask" "B.Paste")
			(net "GND")
		)
		(zone
			(layer "B.Cu")
			(hatch none 0.5)
			(connect_pads
				(clearance 0)
			)
			(min_thickness 0.25)
			(keepout
				(tracks allowed)
				(vias not_allowed)
				(pads allowed)
				(copperpour not_allowed)
				(footprints allowed)
			)
			(placement
				(enabled no)
				(sheetname "")
			)
			(fill
				(thermal_gap 0.5)
				(thermal_bridge_width 0.5)
				(island_removal_mode 0)
			)
			(polygon
				(pts
					(xy 64.0461 -153.8986) (xy 67.0687 -153.8986) (xy 67.0687 -151.003) (xy 67.0687 -150.6728) (xy 64.0461 -150.6728)
					(xy 64.0461 -151.003)
				)
			)
		)
		(zone
			(layer "B.Cu")
			(hatch none 0.5)
			(connect_pads
				(clearance 0)
			)
			(min_thickness 0.25)
			(keepout
				(tracks allowed)
				(vias not_allowed)
				(pads allowed)
				(copperpour not_allowed)
				(footprints allowed)
			)
			(placement
				(enabled no)
				(sheetname "")
			)
			(fill
				(thermal_gap 0.5)
				(thermal_bridge_width 0.5)
				(island_removal_mode 0)
			)
			(polygon
				(pts
					(xy 67.0687 -147.6121) (xy 67.0687 -144.7038) (xy 64.0461 -144.7038) (xy 64.0461 -147.5994) (xy 64.0461 -147.9296)
					(xy 67.0687 -147.9296)
				)
			)
		)
	)
	(footprint ""
		(layer "B.Cu")
		(at 479.933 -230.505)
		(property "Reference" "R1274"
			(at 0 0 0)
			(layer "B.SilkS")
			(hide yes)
			(effects
				(font
					(size 1.27 1.27)
				)
				(justify mirror)
			)
		)
		(property "Value" "71K5R2F-GP"
			(at -0.064008 -3.993896 0)
			(unlocked yes)
			(layer "B.Fab")
			(hide yes)
			(effects
				(font
					(size 1.016 1.016)
					(thickness 0.1524)
				)
				(justify mirror)
			)
		)
		(property "Device Type" "R402H16"
			(at -0.064008 -5.517896 0)
			(unlocked yes)
			(layer "B.Fab")
			(hide yes)
			(effects
				(font
					(size 1.016 1.016)
					(thickness 0.1524)
				)
				(justify mirror)
			)
		)
		(duplicate_pad_numbers_are_jumpers no)
		(fp_line
			(start -0.508 -0.9398)
			(end 0.508 -0.9398)
			(stroke
				(width 0.1524)
				(type default)
			)
			(layer "B.SilkS")
		)
		(fp_line
			(start 0.508 -0.9398)
			(end 0.508 0.9398)
			(stroke
				(width 0.1524)
				(type default)
			)
			(layer "B.SilkS")
		)
		(fp_rect
			(start 0.508 0.9398)
			(end -0.508 -0.9398)
			(stroke
				(width 0)
				(type default)
			)
			(fill no)
			(layer "B.CrtYd")
		)
		(fp_rect
			(start 0.508 0.9398)
			(end -0.508 -0.9398)
			(stroke
				(width 0)
				(type default)
			)
			(fill no)
			(layer "B.Fab")
		)
		(pad "1" smd custom
			(at 0 -0.4445 180)
			(size 0.1397 0.1397)
			(layers "B.Cu" "B.Mask" "B.Paste")
			(net "P5V_D_VFB")
			(options
				(clearance outline)
				(anchor circle)
			)
			(primitives
				(gr_poly
					(pts
						(arc
							(start -0.1778 0.2794)
							(mid -0.249642 0.249642)
							(end -0.2794 0.1778)
						)
						(arc
							(start -0.2794 -0.1778)
							(mid -0.249642 -0.249642)
							(end -0.1778 -0.2794)
						)
						(arc
							(start 0.1778 -0.2794)
							(mid 0.249642 -0.249642)
							(end 0.2794 -0.1778)
						)
						(arc
							(start 0.2794 0.1778)
							(mid 0.249642 0.249642)
							(end 0.1778 0.2794)
						)
					)
					(width 0)
					(fill yes)
				)
			)
		)
		(pad "2" smd custom
			(at 0 0.4445 180)
			(size 0.1397 0.1397)
			(layers "B.Cu" "B.Mask" "B.Paste")
			(net "P5V_D_VFB_R")
			(options
				(clearance outline)
				(anchor circle)
			)
			(primitives
				(gr_poly
					(pts
						(arc
							(start -0.1778 0.2794)
							(mid -0.249642 0.249642)
							(end -0.2794 0.1778)
						)
						(arc
							(start -0.2794 -0.1778)
							(mid -0.249642 -0.249642)
							(end -0.1778 -0.2794)
						)
						(arc
							(start 0.1778 -0.2794)
							(mid 0.249642 -0.249642)
							(end 0.2794 -0.1778)
						)
						(arc
							(start 0.2794 0.1778)
							(mid 0.249642 0.249642)
							(end 0.1778 0.2794)
						)
					)
					(width 0)
					(fill yes)
				)
			)
		)
	)
	(footprint ""
		(layer "B.Cu")
		(at 269.534132 -100.221796 -90)
		(property "Reference" "C39"
			(at 0 0 90)
			(layer "B.SilkS")
			(hide yes)
			(effects
				(font
					(size 1.27 1.27)
				)
				(justify mirror)
			)
		)
		(property "Value" "SC2D2U25V5KX-2-GP"
			(at 0.0762 -6.1214 270)
			(unlocked yes)
			(layer "B.Fab")
			(hide yes)
			(effects
				(font
					(size 1.016 1.016)
					(thickness 0.1524)
				)
				(justify mirror)
			)
		)
		(property "Device Type" "C805H54"
			(at 0.0762 -8.1534 270)
			(unlocked yes)
			(layer "B.Fab")
			(hide yes)
			(effects
				(font
					(size 1.016 1.016)
					(thickness 0.1524)
				)
				(justify mirror)
			)
		)
		(duplicate_pad_numbers_are_jumpers no)
		(fp_line
			(start -0.635 0)
			(end 0.635 0)
			(stroke
				(width 0.508)
				(type default)
			)
			(layer "B.SilkS")
		)
		(fp_rect
			(start 0.9652 1.778)
			(end -0.9652 -1.778)
			(stroke
				(width 0)
				(type default)
			)
			(fill no)
			(layer "B.CrtYd")
		)
		(fp_poly
			(pts
				(xy 0.9652 -1.778) (xy -0.9652 -1.778) (xy -0.9652 1.778) (xy 0.9652 1.778)
			)
			(stroke
				(width 0)
				(type default)
			)
			(fill no)
			(layer "B.Fab")
		)
		(pad "1" smd rect
			(at 0 -0.9652 90)
			(size 1.397 1.143)
			(layers "B.Cu" "B.Mask" "B.Paste")
			(net "P12V_B_COMP")
		)
		(pad "2" smd rect
			(at 0 0.9652 90)
			(size 1.397 1.143)
			(layers "B.Cu" "B.Mask" "B.Paste")
			(net "GND")
		)
	)
	(footprint ""
		(layer "B.Cu")
		(at 348.742 -151.4856 90)
		(property "Reference" "D38"
			(at 0 0 90)
			(layer "B.SilkS")
			(hide yes)
			(effects
				(font
					(size 1.27 1.27)
				)
				(justify mirror)
			)
		)
		(property "Value" "SMCJ14A-13-F-GP"
			(at 4.445 1.1684 90)
			(unlocked yes)
			(layer "B.Fab")
			(hide yes)
			(effects
				(font
					(size 1.016 1.016)
					(thickness 0.1524)
				)
				(justify mirror)
			)
		)
		(property "Device Type" "D795930AKH104"
			(at 4.445 -0.3556 90)
			(unlocked yes)
			(layer "B.Fab")
			(hide yes)
			(effects
				(font
					(size 1.016 1.016)
					(thickness 0.1524)
				)
				(justify mirror)
			)
		)
		(duplicate_pad_numbers_are_jumpers no)
		(fp_line
			(start 3.2004 -4.8641)
			(end 3.2004 4.8641)
			(stroke
				(width 0.1524)
				(type default)
			)
			(layer "B.SilkS")
		)
		(fp_line
			(start -3.2004 -4.8641)
			(end 3.2004 -4.8641)
			(stroke
				(width 0.1524)
				(type default)
			)
			(layer "B.SilkS")
		)
		(fp_line
			(start 3.2004 4.8641)
			(end -3.2004 4.8641)
			(stroke
				(width 0.1524)
				(type default)
			)
			(layer "B.SilkS")
		)
		(fp_line
			(start -3.2004 4.8641)
			(end -3.2004 -4.8641)
			(stroke
				(width 0.1524)
				(type default)
			)
			(layer "B.SilkS")
		)
		(fp_line
			(start -3.2004 5.0419)
			(end 3.2004 5.0419)
			(stroke
				(width 0.508)
				(type default)
			)
			(layer "B.SilkS")
		)
		(fp_poly
			(pts
				(xy 2.9464 3.429) (xy 1.4859 3.429) (xy 1.4859 3.9751) (xy -1.4859 3.9751) (xy -1.4859 3.429) (xy -2.9464 3.429)
				(xy -2.9464 -3.429) (xy -1.4859 -3.429) (xy -1.4859 -3.9751) (xy 1.4859 -3.9751) (xy 1.4859 -3.429)
				(xy 2.9464 -3.429)
			)
			(stroke
				(width 0)
				(type default)
			)
			(fill no)
			(layer "B.CrtYd")
		)
		(fp_poly
			(pts
				(xy 3.4544 4.9403) (xy 3.4544 -4.9403) (xy -3.4544 -4.9403) (xy -3.4544 -3.429) (xy -1.4859 -3.429)
				(xy -1.4859 -3.9751) (xy 1.4859 -3.9751) (xy 1.4859 -3.429) (xy 2.9464 -3.429) (xy 2.9464 3.429)
				(xy 1.4859 3.429) (xy 1.4859 3.9751) (xy -1.4859 3.9751) (xy -1.4859 3.429) (xy -2.9464 3.429) (xy -2.9464 -3.4163)
				(xy -3.4544 -3.4163) (xy -3.4544 4.9403)
			)
			(stroke
				(width 0)
				(type default)
			)
			(fill no)
			(layer "B.CrtYd")
		)
		(fp_rect
			(start 3.4544 4.9403)
			(end -3.4544 -4.9403)
			(stroke
				(width 0)
				(type default)
			)
			(fill no)
			(layer "B.Fab")
		)
		(pad "A" smd rect
			(at 0 -3.592068 270)
			(size 3.2258 2.032)
			(layers "B.Cu" "B.Mask" "B.Paste")
			(net "GND")
		)
		(pad "K" smd rect
			(at 0 3.592068 270)
			(size 3.2258 2.032)
			(layers "B.Cu" "B.Mask" "B.Paste")
			(net "P12V_B")
		)
	)
	(footprint ""
		(layer "B.Cu")
		(at 474.091 -237.871 90)
		(property "Reference" "C651"
			(at 0 0 90)
			(layer "B.SilkS")
			(hide yes)
			(effects
				(font
					(size 1.27 1.27)
				)
				(justify mirror)
			)
		)
		(property "Value" "SCD1U16V2KX-3GP"
			(at -1.1811 -2.7051 90)
			(unlocked yes)
			(layer "B.Fab")
			(hide yes)
			(effects
				(font
					(size 1.016 1.016)
					(thickness 0.1524)
				)
				(justify mirror)
			)
		)
		(property "Device Type" "C402H22"
			(at -1.1811 -4.2291 90)
			(unlocked yes)
			(layer "B.Fab")
			(hide yes)
			(effects
				(font
					(size 1.016 1.016)
					(thickness 0.1524)
				)
				(justify mirror)
			)
		)
		(duplicate_pad_numbers_are_jumpers no)
		(fp_rect
			(start 0.4318 0.9525)
			(end -0.4318 -0.9525)
			(stroke
				(width 0)
				(type default)
			)
			(fill no)
			(layer "B.CrtYd")
		)
		(fp_rect
			(start 0.4318 0.9525)
			(end -0.4318 -0.9525)
			(stroke
				(width 0)
				(type default)
			)
			(fill no)
			(layer "B.Fab")
		)
		(pad "1" smd custom
			(at 0 -0.4445 270)
			(size 0.1524 0.1524)
			(layers "B.Cu" "B.Mask" "B.Paste")
			(net "P12V_A_VIN_U27")
			(options
				(clearance outline)
				(anchor circle)
			)
			(primitives
				(gr_poly
					(pts
						(arc
							(start 0.3048 0.2032)
							(mid 0.275042 0.275042)
							(end 0.2032 0.3048)
						)
						(arc
							(start -0.2032 0.3048)
							(mid -0.275042 0.275042)
							(end -0.3048 0.2032)
						)
						(arc
							(start -0.3048 -0.2032)
							(mid -0.275042 -0.275042)
							(end -0.2032 -0.3048)
						)
						(arc
							(start 0.2032 -0.3048)
							(mid 0.275042 -0.275042)
							(end 0.3048 -0.2032)
						)
					)
					(width 0)
					(fill yes)
				)
			)
		)
		(pad "2" smd custom
			(at 0 0.4445 270)
			(size 0.1524 0.1524)
			(layers "B.Cu" "B.Mask" "B.Paste")
			(net "GND")
			(options
				(clearance outline)
				(anchor circle)
			)
			(primitives
				(gr_poly
					(pts
						(arc
							(start 0.3048 0.2032)
							(mid 0.275042 0.275042)
							(end 0.2032 0.3048)
						)
						(arc
							(start -0.2032 0.3048)
							(mid -0.275042 0.275042)
							(end -0.3048 0.2032)
						)
						(arc
							(start -0.3048 -0.2032)
							(mid -0.275042 -0.275042)
							(end -0.2032 -0.3048)
						)
						(arc
							(start 0.2032 -0.3048)
							(mid 0.275042 -0.275042)
							(end 0.3048 -0.2032)
						)
					)
					(width 0)
					(fill yes)
				)
			)
		)
	)
	(footprint ""
		(layer "B.Cu")
		(at 23.772622 -249.22353 90)
		(property "Reference" "C606"
			(at 0 0 90)
			(layer "B.SilkS")
			(hide yes)
			(effects
				(font
					(size 1.27 1.27)
				)
				(justify mirror)
			)
		)
		(property "Value" "SC1U16V3KX-5GP"
			(at 0 -2.8194 90)
			(unlocked yes)
			(layer "B.Fab")
			(hide yes)
			(effects
				(font
					(size 1.016 1.016)
					(thickness 0.1524)
				)
				(justify mirror)
			)
		)
		(property "Device Type" "C603H36"
			(at 0 -4.3434 90)
			(unlocked yes)
			(layer "B.Fab")
			(hide yes)
			(effects
				(font
					(size 1.016 1.016)
					(thickness 0.1524)
				)
				(justify mirror)
			)
		)
		(duplicate_pad_numbers_are_jumpers no)
		(fp_line
			(start -0.508 0)
			(end 0.508 0)
			(stroke
				(width 0.2032)
				(type default)
			)
			(layer "B.SilkS")
		)
		(fp_rect
			(start 0.5842 1.3335)
			(end -0.5842 -1.3335)
			(stroke
				(width 0)
				(type default)
			)
			(fill no)
			(layer "B.CrtYd")
		)
		(fp_rect
			(start 0.5842 1.3335)
			(end -0.5842 -1.3335)
			(stroke
				(width 0)
				(type default)
			)
			(fill no)
			(layer "B.Fab")
		)
		(pad "1" smd custom
			(at 0 -0.762 270)
			(size 0.2159 0.2159)
			(layers "B.Cu" "B.Mask" "B.Paste")
			(net "GND")
			(options
				(clearance outline)
				(anchor circle)
			)
			(primitives
				(gr_poly
					(pts
						(arc
							(start -0.3302 0.4318)
							(mid -0.402042 0.402042)
							(end -0.4318 0.3302)
						)
						(arc
							(start -0.4318 -0.3302)
							(mid -0.402042 -0.402042)
							(end -0.3302 -0.4318)
						)
						(arc
							(start 0.3302 -0.4318)
							(mid 0.402042 -0.402042)
							(end 0.4318 -0.3302)
						)
						(arc
							(start 0.4318 0.3302)
							(mid 0.402042 0.402042)
							(end 0.3302 0.4318)
						)
					)
					(width 0)
					(fill yes)
				)
			)
		)
		(pad "2" smd custom
			(at 0 0.762 270)
			(size 0.2159 0.2159)
			(layers "B.Cu" "B.Mask" "B.Paste")
			(net "P5V_A_VREG")
			(options
				(clearance outline)
				(anchor circle)
			)
			(primitives
				(gr_poly
					(pts
						(arc
							(start -0.3302 0.4318)
							(mid -0.402042 0.402042)
							(end -0.4318 0.3302)
						)
						(arc
							(start -0.4318 -0.3302)
							(mid -0.402042 -0.402042)
							(end -0.3302 -0.4318)
						)
						(arc
							(start 0.3302 -0.4318)
							(mid 0.402042 -0.402042)
							(end 0.4318 -0.3302)
						)
						(arc
							(start 0.4318 0.3302)
							(mid 0.402042 0.402042)
							(end 0.3302 0.4318)
						)
					)
					(width 0)
					(fill yes)
				)
			)
		)
	)
)
